# HONEY BADGER PTB(D)GCE-1A BOM of 55.B0714.D01G_20150213.xlsx — Primary and Alternate BOM of 55 (bom)
| Level | Parent Number | Part Number | Description | Green Factor | Life Cycle State | Manufacturer | Manufacturer Part Number | Source | BOM Usage | M/P Code | S/D | Qty | UoM | Location |
| 1 | 55.B0714.D01G | 022.40008.0011 | SW PUSH BUTTON 3P MS-B1PL-10 DIP ,PA66 | R2_SA; | Released | WELLBUYING | MS-B1PL-10 | Single |  | Purchase | DIP | 1 | PCS | SW1 |
| 1 | 55.B0714.D01G | 20.81942.024 | CONN CTR 4P+20S RT 51939-689LF ,PA66 | R2_SA; | Released | FCI | 51939-689LF | Single |  | Purchase | DIP | 1 | PCS | CN4 |
| 1 | 55.B0714.D01G | 55.B0714.S01G | HONEY BADGER PTB (S) GCE-1A | N/A; | Released |  |  |  | E | Manufacture | DIP | 1 | PCS |  |
| 2 | 55.B0714.S01G | 48.64W23.01A | PCB 14629-1A HONEY BADGER PTB CARD 4L GC | R2_C; | Released | GCE |  | Single |  | Purchase | SMT | 1 | PCS |  |
| 2 | 55.B0714.S01G | 63.00000.00L | CHIP RES 0 J 1/10W 0603 | R2_SA;HF_SA;G_SA; | Released | TA-I ; RALEC ; YAGEO ; WALSIN | RM06JTN0 ; RTT03000JTP ; RC0603JR-070RL ; WR06X000PTL | Multiple |  | Purchase | SMT | 1 | PCS | PR65 |
| 2 | 55.B0714.S01G | 63.68031.16L | CHIP RES 68 J 1/8W 0805 | R2_SA;HF_SA;G_SA; | Released | RALEC ; TA-I ; YAGEO | RTT05680JTP ; RM10JTN680 ; RC0805JR-0768RL | Multiple |  | Purchase | SMT | 1 | PCS | R378 |
| 2 | 55.B0714.S01G | 63.R0034.1DL | CHIP RES 0 J 1/16W 0402 | R2_SA;HF_SA;G_SA; | Released | TA-I;RALEC;CYNTEC;YAGEO;WALSIN | RM04JTN0;RTT02000JTH;RR0510X-000-XN;RC0402JR-070RL;WR04X000PTL | Multiple |  | Purchase | SMT | 12 | PCS | R366 R384 R385 R386 R387 R388 R389 R390 R391 R480 R481 R482 |
| 2 | 55.B0714.S01G | 64.10005.6DL | CHIP RES 100 F 1/16W 0402 | R2_SA;HF_SA;G_SA; | Released | TA-I ; RALEC ; CYNTEC ; YAGEO;WALSIN | RM04FTN1000 ; RTT021000FTH ; RR0510S-1000-FN ; RC0402FR-07100RL;WR04X1000FTL | Multiple |  | Purchase | SMT | 1 | PCS | R375 |
| 2 | 55.B0714.S01G | 64.10025.6DL | CHIP RES 10K F 1/16W 0402 | R2_SA;HF_SA;G_SA; | Released | TA-I;RALEC;CYNTEC;YAGEO;WALSIN | RM04FTN1002 ; RTT021002FTH ; RR0510S-103-FN ; RC0402FR-0710KL;WR04X1002FTL | Multiple |  | Purchase | SMT | 5 | PCS | R342 R343 R344 R353 R379 |
| 2 | 55.B0714.S01G | 64.10035.6DL | CHIP RES 100K F 1/16W 0402 | R2_SA;HF_SA;G_SA; | Released | TA-I;RALEC;CYNTEC;YAGEO;WALSIN | RM04FTN1003 ; RTT021003FTH ; RR0510S-104-FN ; RC0402FR-07100KL;WR04X1003FTL | Multiple |  | Purchase | SMT | 1 | PCS | R376 |
| 2 | 55.B0714.S01G | 64.20015.55L | CHIP RES 2K F 1/10W 0603 | R2_SA;HF_SA;G_SA; | Released | TA-I ; RALEC ; YAGEO;WALSIN | RM06FTN2001 ; RTT032001FTP ; RC0603FR-072KL;WR06X2001FTL | Multiple |  | Purchase | SMT | 1 | PCS | R483 |
| 2 | 55.B0714.S01G | 64.47035.6DL | CHIP RES 470K F 1/16W 0402 | R2_SA;HF_SA;G_SA; | Released | TA-I;RALEC;CYNTEC;YAGEO;WALSIN | RM04FTN4703;RTT024703FTH;RR0510S-474-FN;RC0402FR-07470KL;WR04X4703FTL | Multiple |  | Purchase | SMT | 1 | PCS | R374 |
| 2 | 55.B0714.S01G | 71.P9511.00W | IC BUF PCA9511ADP-T TSSOP 8P | R2_SA; | Released | NXP | PCA9511ADP-T | Single |  | Purchase | SMT | 1 | PCS | U51 |
| 2 | 55.B0714.S01G | 75.00325.010 | XTOR PHOTO SFH325-3 SMD BJ | R2_SA; | Released | OSRAM | SFH325-3 | Single |  | Purchase | SMT | 1 | PCS | Q31 |
| 2 | 55.B0714.S01G | 75.00426.010 | LED IR EMITT SFH426 SMD | R2_SA; | Released | OSRAM | SFH426 | Single |  | Purchase | SMT | 1 | PCS | LED16 |
| 2 | 55.B0714.S01G | 77.26861.05L | CHIP CAP POS 68U 16V M7343 ESR | R2_SA; | Released | SANYO | 16TQC68MY | Single |  | Purchase | SMT | 3 | PCS | TC3 TC4 TC5 |
| 2 | 55.B0714.S01G | 78.10324.2FL | CHIP CAP C 0.01U 50V K0402 X7R | R2_SA;HF_SA;G_SA; | Released | MURATA;PHYCOMP;DARFON;TDK;SAMSUNG;WALSIN;MURATA | GRM155R71H103KA88D;223858715636;C1005X7R103KGT;C1005X7R1H103KT;CL05B103KB5NNNC;0402B103K500CT;WBM155R71H103KA01D | Multiple |  | Purchase | SMT | 1 | PCS | C345 |
| 2 | 55.B0714.S01G | 78.10424.2BL | CHIP CAP C 0.1U 50V K0603 X7R | R2_SA;HF_SA;G_SA; | Released | MURATA;TDK;AVX;PHYCOMP;SAMSUNG;DARFON;MATSUKI;WALSIN | GRM188R71H104KA93D;C1608X7R1H104KT000N;06035C104KAT2A;223858615649;CL10B104KB8NNNC;C1608X7R104KGT;MAG03X7R1H104K;0603B104K500CT | Multiple |  | Purchase | SMT | 1 | PCS | C344 |
| 2 | 55.B0714.S01G | 78.10622.51L | CHIP CAP C 10U 25V K0805 X5R | R2_SA;HF_SA;G_SA; | Released | MATSUKI;SAMSUNG;TAIYO;AVX;MURATA;TDK;YAGEO | MAG05X5R1E106K;CL21A106KAYNNNE;TMK212BJ106KG-TD;CM21X5R106K25AT;GRM21BR61E106KA73L;C2012X5R1E106KT;CC0805KKX5R8BB106 | Multiple |  | Purchase | SMT | 3 | PCS | C348 C349 C355 |
| 2 | 55.B0714.S01G | 83.00191.K70 | LED GREEN LTST-C191KGKT-5A SMD | R2_SA;HF_SA; | Released | LITEON | LTST-C191KGKT-5A | Single |  | Purchase | SMT | 1 | PCS | LED1 |
| 2 | 55.B0714.S01G | 84.02222.V11 | XTOR MMBT2222A NPN SOT-23 | R2_SA;HF_SA;G_SA; | Released | PANJIT | MMBT2222A | Single |  | Purchase | SMT | 1 | PCS | Q33 |
| 2 | 55.B0714.S01G | 84.27002.W31 | FET MOS 2N7002 NC SOT-23 | R2_SA;HF_SA;G_SA; | Released | PANJIT | 2N7002 | Single |  | Purchase | SMT | 1 | PCS | Q34 |
| 1 | 55.B0714.D01G | 60.B0729.001 | ASSY PTB MAYLAR HB | R2_C; | Released | TBD |  | Single | M | Purchase | DIP | 1 | PCS |  |
| 1 | 55.B0714.D01G | 86.00Q43.140 | SCRW NUT HEX M3 | R_SA;G_SA; | Released | TBD |  | Single |  | Purchase | DIP | 2 | PCS |  |
| 1 | 55.B0714.D01G | 86.1A524.100 | SCRW MACH PAN M3*10L | R_SA; | Released | TBD |  | Single |  | Purchase | DIP | 2 | PCS |  |
